# BASEBOARD_FAB2 (Tioga Pass) — schematic netlist excerpt (pin names and nets, part order shuffled) for the footprints in the layout excerpt that follows; sources: Cadence DE-HDL packaged netlist, KiCad conversion of Wiwynn_Tioga_Pass_MB.brd

R8G25  RES  22.1 1.0% CHIP  pkg 0402  page 101 : A = CLK_50M_CKMNG_SPRVLLE_R ; B = CLK_50M_CKMNG_SPRVLLE
C7G37  CAP  1.0UF 16V 10% X6S  pkg 0402  page 216 : A = VR_FET_SW_P12V_STBY_PVDDQ_ABC ; B = GND

(kicad_pcb
	(version 20260206)
	(generator "pcbnew")
	(generator_version "10.0")
	(general
		(thickness 1.6)
		(legacy_teardrops no)
	)
	(paper "A4")
	(title_block
		(title "Wiwynn_Tioga_Pass_MB.brd")
		(comment 1 "Tioga Pass / footprints 1211-1212 of 4770")
	)
	(layers
		(0 "F.Cu" signal "TOP")
		(4 "In1.Cu" signal "L2GND")
		(6 "In2.Cu" signal "L3")
		(8 "In3.Cu" signal "L4GND")
		(10 "In4.Cu" signal "L5")
		(12 "In5.Cu" signal "L6GND")
		(14 "In6.Cu" signal "L7VCC")
		(16 "In7.Cu" signal "L8VCC")
		(18 "In8.Cu" signal "L9GND")
		(20 "In9.Cu" signal "L10")
		(22 "In10.Cu" signal "L11GND")
		(24 "In11.Cu" signal "L12")
		(26 "In12.Cu" signal "L13GND")
		(2 "B.Cu" signal "BOTTOM")
		(9 "F.Adhes" user "F.Adhesive")
		(11 "B.Adhes" user "B.Adhesive")
		(13 "F.Paste" user "Package Geometry/Pastemask Top")
		(15 "B.Paste" user "Package Geometry/Pastemask Bottom")
		(5 "F.SilkS" user "Ref Des/Silkscreen Top")
		(7 "B.SilkS" user "Ref Des/Silkscreen Bottom")
		(1 "F.Mask" user "Board Geometry/Soldermask Top")
		(3 "B.Mask" user "Board Geometry/Soldermask Bottom")
		(17 "Dwgs.User" user "User.Drawings")
		(19 "Cmts.User" user "User.Comments")
		(21 "Eco1.User" user "User.Eco1")
		(23 "Eco2.User" user "User.Eco2")
		(25 "Edge.Cuts" user "Board Geometry/Outline")
		(27 "Margin" user)
		(31 "F.CrtYd" user "Package Geometry/Place Bound Top")
		(29 "B.CrtYd" user "Package Geometry/Place Bound Bottom")
		(35 "F.Fab" user "Ref Des/Assembly Top")
		(33 "B.Fab" user "Ref Des/Assembly Bottom")
	)
	(footprint ""
		(layer "F.Cu")
		(at 477.139 -36.6395 180)
		(property "Reference" "R8G25"
			(at 0 0 180)
			(layer "F.SilkS")
			(hide yes)
			(effects
				(font
					(size 1.27 1.27)
				)
			)
		)
		(property "Value" ""
			(at 0 0 180)
			(layer "F.Fab")
			(effects
				(font
					(size 1.27 1.27)
				)
			)
		)
		(duplicate_pad_numbers_are_jumpers no)
		(fp_poly
			(pts
				(xy -0.2794 -0.1016) (xy 0.2794 -0.1016) (xy 0.2794 0.9906) (xy -0.2794 0.9906)
			)
			(stroke
				(width 0)
				(type default)
			)
			(fill no)
			(layer "F.CrtYd")
		)
		(fp_line
			(start 0.2794 0.9906)
			(end 0.2794 -0.1016)
			(stroke
				(width 0.1)
				(type default)
			)
			(layer "F.Fab")
		)
		(fp_line
			(start 0.2794 -0.1016)
			(end -0.2794 -0.1016)
			(stroke
				(width 0.1)
				(type default)
			)
			(layer "F.Fab")
		)
		(fp_line
			(start -0.2794 0.9906)
			(end 0.2794 0.9906)
			(stroke
				(width 0.1)
				(type default)
			)
			(layer "F.Fab")
		)
		(fp_line
			(start -0.2794 -0.1016)
			(end -0.2794 0.9906)
			(stroke
				(width 0.1)
				(type default)
			)
			(layer "F.Fab")
		)
		(pad "1" smd rect
			(at 0 0 180)
			(size 0.508 0.508)
			(layers "F.Cu" "F.Mask" "F.Paste")
			(net "CLK_50M_CKMNG_SPRVLLE_R")
		)
		(pad "2" smd rect
			(at 0 0.889 180)
			(size 0.508 0.508)
			(layers "F.Cu" "F.Mask" "F.Paste")
			(net "CLK_50M_CKMNG_SPRVLLE")
		)
		(zone
			(layer "F.Cu")
			(hatch none 0.5)
			(connect_pads
				(clearance 0)
			)
			(min_thickness 0.25)
			(keepout
				(tracks not_allowed)
				(vias allowed)
				(pads allowed)
				(copperpour not_allowed)
				(footprints allowed)
			)
			(placement
				(enabled no)
				(sheetname "")
			)
			(fill
				(thermal_gap 0.5)
				(thermal_bridge_width 0.5)
				(island_removal_mode 0)
			)
			(polygon
				(pts
					(xy 477.393 -37.2745) (xy 476.885 -37.2745) (xy 476.885 -36.8935) (xy 477.393 -36.8935)
				)
			)
		)
		(zone
			(layer "F.Cu")
			(hatch none 0.5)
			(connect_pads
				(clearance 0)
			)
			(min_thickness 0.25)
			(keepout
				(tracks allowed)
				(vias not_allowed)
				(pads allowed)
				(copperpour not_allowed)
				(footprints allowed)
			)
			(placement
				(enabled no)
				(sheetname "")
			)
			(fill
				(thermal_gap 0.5)
				(thermal_bridge_width 0.5)
				(island_removal_mode 0)
			)
			(polygon
				(pts
					(xy 477.393 -36.8935) (xy 476.885 -36.8935) (xy 476.885 -37.2745) (xy 477.393 -37.2745)
				)
			)
		)
	)
	(footprint ""
		(layer "F.Cu")
		(at 350.376236 4.434332 90)
		(property "Reference" "C7G37"
			(at 0 0 90)
			(layer "F.SilkS")
			(hide yes)
			(effects
				(font
					(size 1.27 1.27)
				)
			)
		)
		(property "Value" ""
			(at 0 0 90)
			(layer "F.Fab")
			(effects
				(font
					(size 1.27 1.27)
				)
			)
		)
		(duplicate_pad_numbers_are_jumpers no)
		(fp_poly
			(pts
				(xy 0.3048 -0.1016) (xy 0.3048 0.9906) (xy -0.3048 0.9906) (xy -0.3048 -0.1016)
			)
			(stroke
				(width 0)
				(type default)
			)
			(fill no)
			(layer "F.CrtYd")
		)
		(fp_line
			(start 0.3048 -0.1016)
			(end -0.3048 -0.1016)
			(stroke
				(width 0.1)
				(type default)
			)
			(layer "F.Fab")
		)
		(fp_line
			(start -0.3048 -0.1016)
			(end -0.3048 0.9906)
			(stroke
				(width 0.1)
				(type default)
			)
			(layer "F.Fab")
		)
		(fp_line
			(start 0.3048 0.9906)
			(end 0.3048 -0.1016)
			(stroke
				(width 0.1)
				(type default)
			)
			(layer "F.Fab")
		)
		(fp_line
			(start -0.3048 0.9906)
			(end 0.3048 0.9906)
			(stroke
				(width 0.1)
				(type default)
			)
			(layer "F.Fab")
		)
		(pad "1" smd rect
			(at 0 0 90)
			(size 0.508 0.508)
			(layers "F.Cu" "F.Mask" "F.Paste")
			(net "VR_FET_SW_P12V_STBY_PVDDQ_ABC")
		)
		(pad "2" smd rect
			(at 0 0.889 90)
			(size 0.508 0.508)
			(layers "F.Cu" "F.Mask" "F.Paste")
			(net "GND")
		)
		(zone
			(layer "F.Cu")
			(hatch none 0.5)
			(connect_pads
				(clearance 0)
			)
			(min_thickness 0.25)
			(keepout
				(tracks allowed)
				(vias not_allowed)
				(pads allowed)
				(copperpour not_allowed)
				(footprints allowed)
			)
			(placement
				(enabled no)
				(sheetname "")
			)
			(fill
				(thermal_gap 0.5)
				(thermal_bridge_width 0.5)
				(island_removal_mode 0)
			)
			(polygon
				(pts
					(xy 350.630236 4.688332) (xy 350.630236 4.180332) (xy 351.011236 4.180332) (xy 351.011236 4.688332)
				)
			)
		)
		(zone
			(layer "F.Cu")
			(hatch none 0.5)
			(connect_pads
				(clearance 0)
			)
			(min_thickness 0.25)
			(keepout
				(tracks not_allowed)
				(vias allowed)
				(pads allowed)
				(copperpour not_allowed)
				(footprints allowed)
			)
			(placement
				(enabled no)
				(sheetname "")
			)
			(fill
				(thermal_gap 0.5)
				(thermal_bridge_width 0.5)
				(island_removal_mode 0)
			)
			(polygon
				(pts
					(xy 351.011236 4.688332) (xy 351.011236 4.180332) (xy 350.630236 4.180332) (xy 350.630236 4.688332)
				)
			)
		)
	)
)
